(kicad_pcb
	(version 20260206)
	(generator "pcbnew")
	(generator_version "10.0")
	(general
		(thickness 1.6)
		(legacy_teardrops no)
	)
	(paper "A4")
	(title_block
		(title "v1-chassis-manager — T6M_CM_d_v01_1031_1645.brd")
		(comment 1 "Open CloudServer (Microsoft) / footprints 2062-2071 of 2512")
	)
	(layers
		(0 "F.Cu" signal "TOP")
		(4 "In1.Cu" signal "GND1")
		(6 "In2.Cu" signal "IN1")
		(8 "In3.Cu" signal "VCC1")
		(10 "In4.Cu" signal "VCC2")
		(12 "In5.Cu" signal "GND2")
		(14 "In6.Cu" signal "IN2")
		(16 "In7.Cu" signal "IN3")
		(18 "In8.Cu" signal "GND3")
		(2 "B.Cu" signal "BOTTOM")
		(9 "F.Adhes" user "F.Adhesive")
		(11 "B.Adhes" user "B.Adhesive")
		(13 "F.Paste" user "Package Geometry/Pastemask Top")
		(15 "B.Paste" user "Package Geometry/Pastemask Bottom")
		(5 "F.SilkS" user "Ref Des/Silkscreen Top")
		(7 "B.SilkS" user "Ref Des/Silkscreen Bottom")
		(1 "F.Mask" user "Board Geometry/Soldermask Top")
		(3 "B.Mask" user "Board Geometry/Soldermask Bottom")
		(17 "Dwgs.User" user "User.Drawings")
		(19 "Cmts.User" user "User.Comments")
		(21 "Eco1.User" user "User.Eco1")
		(23 "Eco2.User" user "User.Eco2")
		(25 "Edge.Cuts" user "Board Geometry/Outline")
		(27 "Margin" user)
		(31 "F.CrtYd" user "Package Geometry/Place Bound Top")
		(29 "B.CrtYd" user "Package Geometry/Place Bound Bottom")
		(35 "F.Fab" user "Ref Des/Assembly Top")
		(33 "B.Fab" user "Ref Des/Assembly Bottom")
	)
	(footprint ""
		(layer "B.Cu")
		(at 116.586 -51.943 -90)
		(property "Reference" "R1289"
			(at -1.27 0.02667 270)
			(unlocked yes)
			(layer "B.SilkS")
			(effects
				(font
					(size 0.7874 0.5842)
					(thickness 0.1524)
				)
				(justify left mirror)
			)
		)
		(property "Value" ""
			(at 0 0 90)
			(layer "B.Fab")
			(effects
				(font
					(size 1.27 1.27)
				)
				(justify mirror)
			)
		)
		(duplicate_pad_numbers_are_jumpers no)
		(fp_line
			(start -0.7874 0.4064)
			(end 0.7874 0.4064)
			(stroke
				(width 0.1524)
				(type default)
			)
			(layer "B.SilkS")
		)
		(fp_line
			(start 0.7874 0.4064)
			(end 0.7874 -0.4064)
			(stroke
				(width 0.1524)
				(type default)
			)
			(layer "B.SilkS")
		)
		(fp_line
			(start -0.7874 -0.4064)
			(end -0.7874 0.4064)
			(stroke
				(width 0.1524)
				(type default)
			)
			(layer "B.SilkS")
		)
		(fp_line
			(start 0.7874 -0.4064)
			(end -0.7874 -0.4064)
			(stroke
				(width 0.1524)
				(type default)
			)
			(layer "B.SilkS")
		)
		(fp_poly
			(pts
				(xy 0.508 0.2794) (xy 0.508 0.2286) (xy 0.635 0.2286) (xy 0.635 -0.254) (xy 0.5334 -0.254) (xy 0.5334 -0.2794)
				(xy -0.5334 -0.2794) (xy -0.5334 -0.254) (xy -0.635 -0.254) (xy -0.635 0.254) (xy -0.5334 0.254)
				(xy -0.5334 0.2794)
			)
			(stroke
				(width 0)
				(type default)
			)
			(fill no)
			(layer "B.CrtYd")
		)
		(pad "1" smd rect
			(at -0.40005 0 90)
			(size 0.4572 0.508)
			(layers "B.Cu" "B.Mask" "B.Paste")
			(net "SIO_JTAG_CPLD1_TDI_R")
		)
		(pad "2" smd rect
			(at 0.40005 0 90)
			(size 0.4572 0.508)
			(layers "B.Cu" "B.Mask" "B.Paste")
			(net "P3V3_NODE1")
		)
	)
	(footprint ""
		(layer "B.Cu")
		(at 64.899286 -118.758462 -90)
		(property "Reference" "R334"
			(at 5.056632 0.107188 270)
			(unlocked yes)
			(layer "B.SilkS")
			(effects
				(font
					(size 0.7874 0.5842)
					(thickness 0.1524)
				)
				(justify left mirror)
			)
		)
		(property "Value" ""
			(at 0 0 90)
			(layer "B.Fab")
			(effects
				(font
					(size 1.27 1.27)
				)
				(justify mirror)
			)
		)
		(duplicate_pad_numbers_are_jumpers no)
		(fp_line
			(start -0.7874 0.4064)
			(end 0.7874 0.4064)
			(stroke
				(width 0.1524)
				(type default)
			)
			(layer "B.SilkS")
		)
		(fp_line
			(start 0.7874 0.4064)
			(end 0.7874 -0.4064)
			(stroke
				(width 0.1524)
				(type default)
			)
			(layer "B.SilkS")
		)
		(fp_line
			(start -0.7874 -0.4064)
			(end -0.7874 0.4064)
			(stroke
				(width 0.1524)
				(type default)
			)
			(layer "B.SilkS")
		)
		(fp_line
			(start 0.7874 -0.4064)
			(end -0.7874 -0.4064)
			(stroke
				(width 0.1524)
				(type default)
			)
			(layer "B.SilkS")
		)
		(fp_poly
			(pts
				(xy 0.508 0.2794) (xy 0.508 0.2286) (xy 0.635 0.2286) (xy 0.635 -0.254) (xy 0.5334 -0.254) (xy 0.5334 -0.2794)
				(xy -0.5334 -0.2794) (xy -0.5334 -0.254) (xy -0.635 -0.254) (xy -0.635 0.254) (xy -0.5334 0.254)
				(xy -0.5334 0.2794)
			)
			(stroke
				(width 0)
				(type default)
			)
			(fill no)
			(layer "B.CrtYd")
		)
		(pad "1" smd rect
			(at -0.40005 0 90)
			(size 0.4572 0.508)
			(layers "B.Cu" "B.Mask" "B.Paste")
			(net "P3V3_NODE1")
		)
		(pad "2" smd rect
			(at 0.40005 0 90)
			(size 0.4572 0.508)
			(layers "B.Cu" "B.Mask" "B.Paste")
			(net "BMC_ROMA18")
		)
	)
	(footprint ""
		(layer "B.Cu")
		(at 60.81776 -188.126624 -90)
		(property "Reference" "C679"
			(at -4.276598 0.006096 270)
			(unlocked yes)
			(layer "B.SilkS")
			(effects
				(font
					(size 0.7874 0.5842)
					(thickness 0.1524)
				)
				(justify left mirror)
			)
		)
		(property "Value" ""
			(at 0 0 90)
			(layer "B.Fab")
			(effects
				(font
					(size 1.27 1.27)
				)
				(justify mirror)
			)
		)
		(duplicate_pad_numbers_are_jumpers no)
		(fp_line
			(start -0.7874 0.4064)
			(end 0.7874 0.4064)
			(stroke
				(width 0.1524)
				(type default)
			)
			(layer "B.SilkS")
		)
		(fp_line
			(start 0.7874 0.4064)
			(end 0.7874 -0.4064)
			(stroke
				(width 0.1524)
				(type default)
			)
			(layer "B.SilkS")
		)
		(fp_line
			(start 0 0.381)
			(end 0 -0.381)
			(stroke
				(width 0.1524)
				(type default)
			)
			(layer "B.SilkS")
		)
		(fp_line
			(start -0.7874 -0.4064)
			(end -0.7874 0.4064)
			(stroke
				(width 0.1524)
				(type default)
			)
			(layer "B.SilkS")
		)
		(fp_line
			(start 0.7874 -0.4064)
			(end -0.7874 -0.4064)
			(stroke
				(width 0.1524)
				(type default)
			)
			(layer "B.SilkS")
		)
		(fp_poly
			(pts
				(xy 0.5334 0.254) (xy 0.635 0.254) (xy 0.635 0.2286) (xy 0.635 -0.254) (xy 0.5334 -0.254) (xy 0.5334 -0.2794)
				(xy -0.5334 -0.2794) (xy -0.5334 -0.254) (xy -0.635 -0.254) (xy -0.635 0.254) (xy -0.5334 0.254)
				(xy -0.5334 0.2794) (xy 0.508 0.2794) (xy 0.5334 0.2794)
			)
			(stroke
				(width 0)
				(type default)
			)
			(fill no)
			(layer "B.CrtYd")
		)
		(pad "1" smd rect
			(at -0.40005 0 90)
			(size 0.4572 0.508)
			(layers "B.Cu" "B.Mask" "B.Paste")
			(net "UART_T1_NODE2_TXD_R")
		)
		(pad "2" smd rect
			(at 0.40005 0 90)
			(size 0.4572 0.508)
			(layers "B.Cu" "B.Mask" "B.Paste")
			(net "GND")
		)
	)
	(footprint ""
		(layer "B.Cu")
		(at 147.305014 -74.699622)
		(property "Reference" "L31"
			(at 4.93522 -0.838962 0)
			(unlocked yes)
			(layer "B.SilkS")
			(effects
				(font
					(size 0.7874 0.5842)
					(thickness 0.1524)
				)
				(justify left mirror)
			)
		)
		(property "Value" ""
			(at 0 0 0)
			(layer "B.Fab")
			(effects
				(font
					(size 1.27 1.27)
				)
				(justify mirror)
			)
		)
		(duplicate_pad_numbers_are_jumpers no)
		(fp_line
			(start -0.7874 -0.4064)
			(end -0.7874 0.4064)
			(stroke
				(width 0.1524)
				(type default)
			)
			(layer "B.SilkS")
		)
		(fp_line
			(start -0.7874 0.4064)
			(end 0.7874 0.4064)
			(stroke
				(width 0.1524)
				(type default)
			)
			(layer "B.SilkS")
		)
		(fp_line
			(start -0.0889 0.4064)
			(end -0.0889 -0.4064)
			(stroke
				(width 0.1524)
				(type default)
			)
			(layer "B.SilkS")
		)
		(fp_line
			(start 0.0889 0.4064)
			(end 0.0889 -0.4064)
			(stroke
				(width 0.1524)
				(type default)
			)
			(layer "B.SilkS")
		)
		(fp_line
			(start 0.7874 -0.4064)
			(end -0.7874 -0.4064)
			(stroke
				(width 0.1524)
				(type default)
			)
			(layer "B.SilkS")
		)
		(fp_line
			(start 0.7874 0.4064)
			(end 0.7874 -0.4064)
			(stroke
				(width 0.1524)
				(type default)
			)
			(layer "B.SilkS")
		)
		(fp_poly
			(pts
				(xy 0.5334 0.254) (xy 0.635 0.254) (xy 0.635 0.2286) (xy 0.635 -0.254) (xy 0.5334 -0.254) (xy 0.5334 -0.2794)
				(xy -0.5334 -0.2794) (xy -0.5334 -0.254) (xy -0.635 -0.254) (xy -0.635 0.254) (xy -0.5334 0.254)
				(xy -0.5334 0.2794) (xy 0.508 0.2794) (xy 0.5334 0.2794)
			)
			(stroke
				(width 0)
				(type default)
			)
			(fill no)
			(layer "B.CrtYd")
		)
		(pad "1" smd rect
			(at -0.40005 0 180)
			(size 0.4572 0.508)
			(layers "B.Cu" "B.Mask" "B.Paste")
			(net "P1V8_NODE1")
		)
		(pad "2" smd rect
			(at 0.40005 0 180)
			(size 0.4572 0.508)
			(layers "B.Cu" "B.Mask" "B.Paste")
			(net "P1V8_SATA_AVDD_NODE1")
		)
	)
	(footprint ""
		(layer "B.Cu")
		(at 59.67476 -188.126624 90)
		(property "Reference" "R919"
			(at 4.276598 0.050546 270)
			(unlocked yes)
			(layer "B.SilkS")
			(effects
				(font
					(size 0.7874 0.5842)
					(thickness 0.1524)
				)
				(justify left mirror)
			)
		)
		(property "Value" ""
			(at 0 0 90)
			(layer "B.Fab")
			(effects
				(font
					(size 1.27 1.27)
				)
				(justify mirror)
			)
		)
		(duplicate_pad_numbers_are_jumpers no)
		(fp_line
			(start 0.7874 -0.4064)
			(end -0.7874 -0.4064)
			(stroke
				(width 0.1524)
				(type default)
			)
			(layer "B.SilkS")
		)
		(fp_line
			(start -0.7874 -0.4064)
			(end -0.7874 0.4064)
			(stroke
				(width 0.1524)
				(type default)
			)
			(layer "B.SilkS")
		)
		(fp_line
			(start 0.7874 0.4064)
			(end 0.7874 -0.4064)
			(stroke
				(width 0.1524)
				(type default)
			)
			(layer "B.SilkS")
		)
		(fp_line
			(start -0.7874 0.4064)
			(end 0.7874 0.4064)
			(stroke
				(width 0.1524)
				(type default)
			)
			(layer "B.SilkS")
		)
		(fp_poly
			(pts
				(xy 0.508 0.2794) (xy 0.508 0.2286) (xy 0.635 0.2286) (xy 0.635 -0.254) (xy 0.5334 -0.254) (xy 0.5334 -0.2794)
				(xy -0.5334 -0.2794) (xy -0.5334 -0.254) (xy -0.635 -0.254) (xy -0.635 0.254) (xy -0.5334 0.254)
				(xy -0.5334 0.2794)
			)
			(stroke
				(width 0)
				(type default)
			)
			(fill no)
			(layer "B.CrtYd")
		)
		(pad "1" smd rect
			(at -0.40005 0 270)
			(size 0.4572 0.508)
			(layers "B.Cu" "B.Mask" "B.Paste")
			(net "UART_T1_NODE3_RXD")
		)
		(pad "2" smd rect
			(at 0.40005 0 270)
			(size 0.4572 0.508)
			(layers "B.Cu" "B.Mask" "B.Paste")
			(net "UART_T1_NODE3_RXD_R")
		)
	)
	(footprint ""
		(layer "B.Cu")
		(at 137.970006 -37.44341 180)
		(property "Reference" "R1187"
			(at 3.629406 -18.52168 0)
			(unlocked yes)
			(layer "B.SilkS")
			(effects
				(font
					(size 0.7874 0.5842)
					(thickness 0.1524)
				)
				(justify left mirror)
			)
		)
		(property "Value" ""
			(at 0 0 0)
			(layer "B.Fab")
			(effects
				(font
					(size 1.27 1.27)
				)
				(justify mirror)
			)
		)
		(duplicate_pad_numbers_are_jumpers no)
		(fp_line
			(start 0.7874 0.4064)
			(end 0.7874 -0.4064)
			(stroke
				(width 0.1524)
				(type default)
			)
			(layer "B.SilkS")
		)
		(fp_line
			(start 0.7874 -0.4064)
			(end -0.7874 -0.4064)
			(stroke
				(width 0.1524)
				(type default)
			)
			(layer "B.SilkS")
		)
		(fp_line
			(start -0.7874 0.4064)
			(end 0.7874 0.4064)
			(stroke
				(width 0.1524)
				(type default)
			)
			(layer "B.SilkS")
		)
		(fp_line
			(start -0.7874 -0.4064)
			(end -0.7874 0.4064)
			(stroke
				(width 0.1524)
				(type default)
			)
			(layer "B.SilkS")
		)
		(fp_poly
			(pts
				(xy 0.508 0.2794) (xy 0.508 0.2286) (xy 0.635 0.2286) (xy 0.635 -0.254) (xy 0.5334 -0.254) (xy 0.5334 -0.2794)
				(xy -0.5334 -0.2794) (xy -0.5334 -0.254) (xy -0.635 -0.254) (xy -0.635 0.254) (xy -0.5334 0.254)
				(xy -0.5334 0.2794)
			)
			(stroke
				(width 0)
				(type default)
			)
			(fill no)
			(layer "B.CrtYd")
		)
		(pad "1" smd rect
			(at -0.40005 0)
			(size 0.4572 0.508)
			(layers "B.Cu" "B.Mask" "B.Paste")
			(net "SIO_JTAG_CPLD2_TDI_R")
		)
		(pad "2" smd rect
			(at 0.40005 0)
			(size 0.4572 0.508)
			(layers "B.Cu" "B.Mask" "B.Paste")
			(net "SIO_JTAG_CPLD2_TDI")
		)
	)
	(footprint ""
		(layer "B.Cu")
		(at 64.109346 -66.988182 -90)
		(property "Reference" "C119"
			(at 35.382454 14.578076 270)
			(unlocked yes)
			(layer "B.SilkS")
			(effects
				(font
					(size 0.7874 0.5842)
					(thickness 0.1524)
				)
				(justify left mirror)
			)
		)
		(property "Value" ""
			(at 0 0 90)
			(layer "B.Fab")
			(effects
				(font
					(size 1.27 1.27)
				)
				(justify mirror)
			)
		)
		(duplicate_pad_numbers_are_jumpers no)
		(fp_line
			(start -0.7874 0.4064)
			(end 0.7874 0.4064)
			(stroke
				(width 0.1524)
				(type default)
			)
			(layer "B.SilkS")
		)
		(fp_line
			(start 0.7874 0.4064)
			(end 0.7874 -0.4064)
			(stroke
				(width 0.1524)
				(type default)
			)
			(layer "B.SilkS")
		)
		(fp_line
			(start 0 0.381)
			(end 0 -0.381)
			(stroke
				(width 0.1524)
				(type default)
			)
			(layer "B.SilkS")
		)
		(fp_line
			(start -0.7874 -0.4064)
			(end -0.7874 0.4064)
			(stroke
				(width 0.1524)
				(type default)
			)
			(layer "B.SilkS")
		)
		(fp_line
			(start 0.7874 -0.4064)
			(end -0.7874 -0.4064)
			(stroke
				(width 0.1524)
				(type default)
			)
			(layer "B.SilkS")
		)
		(fp_poly
			(pts
				(xy 0.5334 0.254) (xy 0.635 0.254) (xy 0.635 0.2286) (xy 0.635 -0.254) (xy 0.5334 -0.254) (xy 0.5334 -0.2794)
				(xy -0.5334 -0.2794) (xy -0.5334 -0.254) (xy -0.635 -0.254) (xy -0.635 0.254) (xy -0.5334 0.254)
				(xy -0.5334 0.2794) (xy 0.508 0.2794) (xy 0.5334 0.2794)
			)
			(stroke
				(width 0)
				(type default)
			)
			(fill no)
			(layer "B.CrtYd")
		)
		(pad "1" smd rect
			(at -0.40005 0 90)
			(size 0.4572 0.508)
			(layers "B.Cu" "B.Mask" "B.Paste")
			(net "PV_VDDR_NODE1")
		)
		(pad "2" smd rect
			(at 0.40005 0 90)
			(size 0.4572 0.508)
			(layers "B.Cu" "B.Mask" "B.Paste")
			(net "GND")
		)
	)
	(footprint ""
		(layer "B.Cu")
		(at 26.37282 -164.748718)
		(property "Reference" "C511"
			(at 0.4826 2.188972 0)
			(unlocked yes)
			(layer "B.SilkS")
			(effects
				(font
					(size 0.7874 0.5842)
					(thickness 0.1524)
				)
				(justify left mirror)
			)
		)
		(property "Value" ""
			(at 0 0 0)
			(layer "B.Fab")
			(effects
				(font
					(size 1.27 1.27)
				)
				(justify mirror)
			)
		)
		(duplicate_pad_numbers_are_jumpers no)
		(fp_line
			(start -0.7874 -0.4064)
			(end -0.7874 0.4064)
			(stroke
				(width 0.1524)
				(type default)
			)
			(layer "B.SilkS")
		)
		(fp_line
			(start -0.7874 0.4064)
			(end 0.7874 0.4064)
			(stroke
				(width 0.1524)
				(type default)
			)
			(layer "B.SilkS")
		)
		(fp_line
			(start 0 0.381)
			(end 0 -0.381)
			(stroke
				(width 0.1524)
				(type default)
			)
			(layer "B.SilkS")
		)
		(fp_line
			(start 0.7874 -0.4064)
			(end -0.7874 -0.4064)
			(stroke
				(width 0.1524)
				(type default)
			)
			(layer "B.SilkS")
		)
		(fp_line
			(start 0.7874 0.4064)
			(end 0.7874 -0.4064)
			(stroke
				(width 0.1524)
				(type default)
			)
			(layer "B.SilkS")
		)
		(fp_poly
			(pts
				(xy 0.5334 0.254) (xy 0.635 0.254) (xy 0.635 0.2286) (xy 0.635 -0.254) (xy 0.5334 -0.254) (xy 0.5334 -0.2794)
				(xy -0.5334 -0.2794) (xy -0.5334 -0.254) (xy -0.635 -0.254) (xy -0.635 0.254) (xy -0.5334 0.254)
				(xy -0.5334 0.2794) (xy 0.508 0.2794) (xy 0.5334 0.2794)
			)
			(stroke
				(width 0)
				(type default)
			)
			(fill no)
			(layer "B.CrtYd")
		)
		(pad "1" smd rect
			(at -0.40005 0 180)
			(size 0.4572 0.508)
			(layers "B.Cu" "B.Mask" "B.Paste")
			(net "P1V9_LAN1")
		)
		(pad "2" smd rect
			(at 0.40005 0 180)
			(size 0.4572 0.508)
			(layers "B.Cu" "B.Mask" "B.Paste")
			(net "GND")
		)
	)
	(footprint ""
		(layer "B.Cu")
		(at 55.8165 -75.445874 180)
		(property "Reference" "C129"
			(at 13.379196 -31.487364 0)
			(unlocked yes)
			(layer "B.SilkS")
			(effects
				(font
					(size 0.7874 0.5842)
					(thickness 0.1524)
				)
				(justify left mirror)
			)
		)
		(property "Value" ""
			(at 0 0 0)
			(layer "B.Fab")
			(effects
				(font
					(size 1.27 1.27)
				)
				(justify mirror)
			)
		)
		(duplicate_pad_numbers_are_jumpers no)
		(fp_line
			(start 0.7874 0.4064)
			(end 0.7874 -0.4064)
			(stroke
				(width 0.1524)
				(type default)
			)
			(layer "B.SilkS")
		)
		(fp_line
			(start 0.7874 -0.4064)
			(end -0.7874 -0.4064)
			(stroke
				(width 0.1524)
				(type default)
			)
			(layer "B.SilkS")
		)
		(fp_line
			(start 0 0.381)
			(end 0 -0.381)
			(stroke
				(width 0.1524)
				(type default)
			)
			(layer "B.SilkS")
		)
		(fp_line
			(start -0.7874 0.4064)
			(end 0.7874 0.4064)
			(stroke
				(width 0.1524)
				(type default)
			)
			(layer "B.SilkS")
		)
		(fp_line
			(start -0.7874 -0.4064)
			(end -0.7874 0.4064)
			(stroke
				(width 0.1524)
				(type default)
			)
			(layer "B.SilkS")
		)
		(fp_poly
			(pts
				(xy 0.5334 0.254) (xy 0.635 0.254) (xy 0.635 0.2286) (xy 0.635 -0.254) (xy 0.5334 -0.254) (xy 0.5334 -0.2794)
				(xy -0.5334 -0.2794) (xy -0.5334 -0.254) (xy -0.635 -0.254) (xy -0.635 0.254) (xy -0.5334 0.254)
				(xy -0.5334 0.2794) (xy 0.508 0.2794) (xy 0.5334 0.2794)
			)
			(stroke
				(width 0)
				(type default)
			)
			(fill no)
			(layer "B.CrtYd")
		)
		(pad "1" smd rect
			(at -0.40005 0)
			(size 0.4572 0.508)
			(layers "B.Cu" "B.Mask" "B.Paste")
			(net "P1V05_NODE1")
		)
		(pad "2" smd rect
			(at 0.40005 0)
			(size 0.4572 0.508)
			(layers "B.Cu" "B.Mask" "B.Paste")
			(net "GND")
		)
	)
	(footprint ""
		(layer "B.Cu")
		(at 58.015632 -74.371962 -90)
		(property "Reference" "C123"
			(at 32.731964 14.633702 270)
			(unlocked yes)
			(layer "B.SilkS")
			(effects
				(font
					(size 0.7874 0.5842)
					(thickness 0.1524)
				)
				(justify left mirror)
			)
		)
		(property "Value" ""
			(at 0 0 90)
			(layer "B.Fab")
			(effects
				(font
					(size 1.27 1.27)
				)
				(justify mirror)
			)
		)
		(duplicate_pad_numbers_are_jumpers no)
		(fp_line
			(start -0.7874 0.4064)
			(end 0.7874 0.4064)
			(stroke
				(width 0.1524)
				(type default)
			)
			(layer "B.SilkS")
		)
		(fp_line
			(start 0.7874 0.4064)
			(end 0.7874 -0.4064)
			(stroke
				(width 0.1524)
				(type default)
			)
			(layer "B.SilkS")
		)
		(fp_line
			(start 0 0.381)
			(end 0 -0.381)
			(stroke
				(width 0.1524)
				(type default)
			)
			(layer "B.SilkS")
		)
		(fp_line
			(start -0.7874 -0.4064)
			(end -0.7874 0.4064)
			(stroke
				(width 0.1524)
				(type default)
			)
			(layer "B.SilkS")
		)
		(fp_line
			(start 0.7874 -0.4064)
			(end -0.7874 -0.4064)
			(stroke
				(width 0.1524)
				(type default)
			)
			(layer "B.SilkS")
		)
		(fp_poly
			(pts
				(xy 0.5334 0.254) (xy 0.635 0.254) (xy 0.635 0.2286) (xy 0.635 -0.254) (xy 0.5334 -0.254) (xy 0.5334 -0.2794)
				(xy -0.5334 -0.2794) (xy -0.5334 -0.254) (xy -0.635 -0.254) (xy -0.635 0.254) (xy -0.5334 0.254)
				(xy -0.5334 0.2794) (xy 0.508 0.2794) (xy 0.5334 0.2794)
			)
			(stroke
				(width 0)
				(type default)
			)
			(fill no)
			(layer "B.CrtYd")
		)
		(pad "1" smd rect
			(at -0.40005 0 90)
			(size 0.4572 0.508)
			(layers "B.Cu" "B.Mask" "B.Paste")
			(net "P1V05_NODE1")
		)
		(pad "2" smd rect
			(at 0.40005 0 90)
			(size 0.4572 0.508)
			(layers "B.Cu" "B.Mask" "B.Paste")
			(net "GND")
		)
	)
)
